(kicad_pcb
	(version 20260206)
	(generator "pcbnew")
	(generator_version "10.0")
	(general
		(thickness 1.6)
		(legacy_teardrops no)
	)
	(paper "A4")
	(title_block
		(title "Bryce Canyon_SCC_16316-1_OCP.brd")
		(comment 1 "Bryce Canyon / footprints 525-532 of 1561")
	)
	(layers
		(0 "F.Cu" signal "TOP")
		(4 "In1.Cu" signal "L2GND")
		(6 "In2.Cu" signal "L3")
		(8 "In3.Cu" signal "L4VCC")
		(10 "In4.Cu" signal "L5VCC")
		(12 "In5.Cu" signal "L6")
		(14 "In6.Cu" signal "L7GND")
		(2 "B.Cu" signal "BOTTOM")
		(9 "F.Adhes" user "F.Adhesive")
		(11 "B.Adhes" user "B.Adhesive")
		(13 "F.Paste" user "Package Geometry/Pastemask Top")
		(15 "B.Paste" user "Package Geometry/Pastemask Bottom")
		(5 "F.SilkS" user "Ref Des/Silkscreen Top")
		(7 "B.SilkS" user "Ref Des/Silkscreen Bottom")
		(1 "F.Mask" user "Board Geometry/Soldermask Top")
		(3 "B.Mask" user "Board Geometry/Soldermask Bottom")
		(17 "Dwgs.User" user "User.Drawings")
		(19 "Cmts.User" user "User.Comments")
		(21 "Eco1.User" user "User.Eco1")
		(23 "Eco2.User" user "User.Eco2")
		(25 "Edge.Cuts" user "Board Geometry/Outline")
		(27 "Margin" user)
		(31 "F.CrtYd" user "Package Geometry/Place Bound Top")
		(29 "B.CrtYd" user "Package Geometry/Place Bound Bottom")
		(35 "F.Fab" user "Ref Des/Assembly Top")
		(33 "B.Fab" user "Ref Des/Assembly Bottom")
	)
	(footprint ""
		(layer "F.Cu")
		(at 16.146018 -61.552582 -90)
		(property "Reference" "R691"
			(at 0 0 270)
			(layer "F.SilkS")
			(hide yes)
			(effects
				(font
					(size 1.27 1.27)
				)
			)
		)
		(property "Value" "0R2J-2-GP"
			(at 0.064008 -3.993896 270)
			(unlocked yes)
			(layer "F.Fab")
			(hide yes)
			(effects
				(font
					(size 1.016 1.016)
					(thickness 0.1524)
				)
			)
		)
		(property "Device Type" "R402H16"
			(at 0.064008 -5.517896 270)
			(unlocked yes)
			(layer "F.Fab")
			(hide yes)
			(effects
				(font
					(size 1.016 1.016)
					(thickness 0.1524)
				)
			)
		)
		(duplicate_pad_numbers_are_jumpers no)
		(fp_line
			(start -0.508 -0.9398)
			(end -0.508 0.9398)
			(stroke
				(width 0.1524)
				(type default)
			)
			(layer "F.SilkS")
		)
		(fp_line
			(start 0.508 -0.9398)
			(end -0.508 -0.9398)
			(stroke
				(width 0.1524)
				(type default)
			)
			(layer "F.SilkS")
		)
		(fp_rect
			(start -0.508 0.9398)
			(end 0.508 -0.9398)
			(stroke
				(width 0)
				(type default)
			)
			(fill no)
			(layer "F.CrtYd")
		)
		(fp_rect
			(start -0.508 0.9398)
			(end 0.508 -0.9398)
			(stroke
				(width 0)
				(type default)
			)
			(fill no)
			(layer "F.Fab")
		)
		(pad "1" smd custom
			(at 0 -0.4445 270)
			(size 0.1397 0.1397)
			(layers "F.Cu" "F.Mask" "F.Paste")
			(net "SCC_STBY_PWR_BUF_EN")
			(options
				(clearance outline)
				(anchor circle)
			)
			(primitives
				(gr_poly
					(pts
						(arc
							(start -0.1778 -0.2794)
							(mid -0.249642 -0.249642)
							(end -0.2794 -0.1778)
						)
						(arc
							(start -0.2794 0.1778)
							(mid -0.249642 0.249642)
							(end -0.1778 0.2794)
						)
						(arc
							(start 0.1778 0.2794)
							(mid 0.249642 0.249642)
							(end 0.2794 0.1778)
						)
						(arc
							(start 0.2794 -0.1778)
							(mid 0.249642 -0.249642)
							(end 0.1778 -0.2794)
						)
					)
					(width 0)
					(fill yes)
				)
			)
		)
		(pad "2" smd custom
			(at 0 0.4445 270)
			(size 0.1397 0.1397)
			(layers "F.Cu" "F.Mask" "F.Paste")
			(net "MB0_HS_ENABLE")
			(options
				(clearance outline)
				(anchor circle)
			)
			(primitives
				(gr_poly
					(pts
						(arc
							(start -0.1778 -0.2794)
							(mid -0.249642 -0.249642)
							(end -0.2794 -0.1778)
						)
						(arc
							(start -0.2794 0.1778)
							(mid -0.249642 0.249642)
							(end -0.1778 0.2794)
						)
						(arc
							(start 0.1778 0.2794)
							(mid 0.249642 0.249642)
							(end 0.2794 0.1778)
						)
						(arc
							(start 0.2794 -0.1778)
							(mid 0.249642 -0.249642)
							(end 0.1778 -0.2794)
						)
					)
					(width 0)
					(fill yes)
				)
			)
		)
	)
	(footprint ""
		(layer "F.Cu")
		(at 139.414758 -82.308446 180)
		(property "Reference" "VIA28"
			(at 0 0 180)
			(layer "F.SilkS")
			(hide yes)
			(effects
				(font
					(size 1.27 1.27)
				)
			)
		)
		(property "Value" "100OHM-8L-1D6MM-L18L16-GP"
			(at -3.7211 -4.5085 180)
			(unlocked yes)
			(layer "F.Fab")
			(hide yes)
			(effects
				(font
					(size 1.016 1.016)
					(thickness 0.1524)
				)
			)
		)
		(property "Device Type" "VIA-PCIE-4P-394076"
			(at -3.7211 -6.0325 180)
			(unlocked yes)
			(layer "F.Fab")
			(hide yes)
			(effects
				(font
					(size 1.016 1.016)
					(thickness 0.1524)
				)
			)
		)
		(duplicate_pad_numbers_are_jumpers no)
		(fp_rect
			(start -1.9685 0.381)
			(end 1.9685 -0.381)
			(stroke
				(width 0)
				(type default)
			)
			(fill no)
			(layer "F.CrtYd")
		)
		(fp_rect
			(start -1.9685 0.381)
			(end 1.9685 -0.381)
			(stroke
				(width 0)
				(type default)
			)
			(fill no)
			(layer "F.Fab")
		)
		(pad "1" thru_hole circle
			(at -1.5875 0 180)
			(size 0.508 0.508)
			(drill 0.254)
			(layers "*.Cu" "*.Mask")
			(remove_unused_layers no)
			(net "GND")
			(clearance 0.127)
			(thermal_gap 0.127)
		)
		(pad "2" thru_hole circle
			(at -0.5715 0 180)
			(size 0.508 0.508)
			(drill 0.254)
			(layers "*.Cu" "*.Mask")
			(remove_unused_layers no)
			(net "PHY_EXP_TO_CONN_11_DP")
			(clearance 0.127)
			(thermal_gap 0.127)
		)
		(pad "3" thru_hole circle
			(at 0.5715 0 180)
			(size 0.508 0.508)
			(drill 0.254)
			(layers "*.Cu" "*.Mask")
			(remove_unused_layers no)
			(net "PHY_EXP_TO_CONN_11_DN")
			(clearance 0.127)
			(thermal_gap 0.127)
		)
		(pad "4" thru_hole circle
			(at 1.5875 0 180)
			(size 0.508 0.508)
			(drill 0.254)
			(layers "*.Cu" "*.Mask")
			(remove_unused_layers no)
			(net "GND")
			(clearance 0.127)
			(thermal_gap 0.127)
		)
	)
	(footprint ""
		(layer "F.Cu")
		(at 19.252184 -71.55053 90)
		(property "Reference" "R354"
			(at 0 0 90)
			(layer "F.SilkS")
			(hide yes)
			(effects
				(font
					(size 1.27 1.27)
				)
			)
		)
		(property "Value" "0R2J-2-GP"
			(at 0.064008 -3.993896 90)
			(unlocked yes)
			(layer "F.Fab")
			(hide yes)
			(effects
				(font
					(size 1.016 1.016)
					(thickness 0.1524)
				)
			)
		)
		(property "Device Type" "R402H16"
			(at 0.064008 -5.517896 90)
			(unlocked yes)
			(layer "F.Fab")
			(hide yes)
			(effects
				(font
					(size 1.016 1.016)
					(thickness 0.1524)
				)
			)
		)
		(duplicate_pad_numbers_are_jumpers no)
		(fp_line
			(start 0.508 -0.9398)
			(end -0.508 -0.9398)
			(stroke
				(width 0.1524)
				(type default)
			)
			(layer "F.SilkS")
		)
		(fp_line
			(start -0.508 -0.9398)
			(end -0.508 0.9398)
			(stroke
				(width 0.1524)
				(type default)
			)
			(layer "F.SilkS")
		)
		(fp_rect
			(start -0.508 0.9398)
			(end 0.508 -0.9398)
			(stroke
				(width 0)
				(type default)
			)
			(fill no)
			(layer "F.CrtYd")
		)
		(fp_rect
			(start -0.508 0.9398)
			(end 0.508 -0.9398)
			(stroke
				(width 0)
				(type default)
			)
			(fill no)
			(layer "F.Fab")
		)
		(pad "1" smd custom
			(at 0 -0.4445 90)
			(size 0.1397 0.1397)
			(layers "F.Cu" "F.Mask" "F.Paste")
			(net "EEPROM_SCL")
			(options
				(clearance outline)
				(anchor circle)
			)
			(primitives
				(gr_poly
					(pts
						(arc
							(start -0.1778 -0.2794)
							(mid -0.249642 -0.249642)
							(end -0.2794 -0.1778)
						)
						(arc
							(start -0.2794 0.1778)
							(mid -0.249642 0.249642)
							(end -0.1778 0.2794)
						)
						(arc
							(start 0.1778 0.2794)
							(mid 0.249642 0.249642)
							(end 0.2794 0.1778)
						)
						(arc
							(start 0.2794 -0.1778)
							(mid 0.249642 -0.249642)
							(end 0.1778 -0.2794)
						)
					)
					(width 0)
					(fill yes)
				)
			)
		)
		(pad "2" smd custom
			(at 0 0.4445 90)
			(size 0.1397 0.1397)
			(layers "F.Cu" "F.Mask" "F.Paste")
			(net "I2C_SCC_SCL2")
			(options
				(clearance outline)
				(anchor circle)
			)
			(primitives
				(gr_poly
					(pts
						(arc
							(start -0.1778 -0.2794)
							(mid -0.249642 -0.249642)
							(end -0.2794 -0.1778)
						)
						(arc
							(start -0.2794 0.1778)
							(mid -0.249642 0.249642)
							(end -0.1778 0.2794)
						)
						(arc
							(start 0.1778 0.2794)
							(mid 0.249642 0.249642)
							(end 0.2794 0.1778)
						)
						(arc
							(start 0.2794 -0.1778)
							(mid 0.249642 -0.249642)
							(end 0.1778 -0.2794)
						)
					)
					(width 0)
					(fill yes)
				)
			)
		)
	)
	(footprint ""
		(layer "F.Cu")
		(at 174.34306 -108.34878)
		(property "Reference" "R443"
			(at 0 0 0)
			(layer "F.SilkS")
			(hide yes)
			(effects
				(font
					(size 1.27 1.27)
				)
			)
		)
		(property "Value" "4K7R2F-GP"
			(at 0.064008 -3.993896 0)
			(unlocked yes)
			(layer "F.Fab")
			(hide yes)
			(effects
				(font
					(size 1.016 1.016)
					(thickness 0.1524)
				)
			)
		)
		(property "Device Type" "R402H16"
			(at 0.064008 -5.517896 0)
			(unlocked yes)
			(layer "F.Fab")
			(hide yes)
			(effects
				(font
					(size 1.016 1.016)
					(thickness 0.1524)
				)
			)
		)
		(duplicate_pad_numbers_are_jumpers no)
		(fp_line
			(start -0.508 -0.9398)
			(end -0.508 0.9398)
			(stroke
				(width 0.1524)
				(type default)
			)
			(layer "F.SilkS")
		)
		(fp_line
			(start 0.508 -0.9398)
			(end -0.508 -0.9398)
			(stroke
				(width 0.1524)
				(type default)
			)
			(layer "F.SilkS")
		)
		(fp_rect
			(start -0.508 0.9398)
			(end 0.508 -0.9398)
			(stroke
				(width 0)
				(type default)
			)
			(fill no)
			(layer "F.CrtYd")
		)
		(fp_rect
			(start -0.508 0.9398)
			(end 0.508 -0.9398)
			(stroke
				(width 0)
				(type default)
			)
			(fill no)
			(layer "F.Fab")
		)
		(pad "1" smd custom
			(at 0 -0.4445)
			(size 0.1397 0.1397)
			(layers "F.Cu" "F.Mask" "F.Paste")
			(net "P1V8_C")
			(options
				(clearance outline)
				(anchor circle)
			)
			(primitives
				(gr_poly
					(pts
						(arc
							(start -0.1778 -0.2794)
							(mid -0.249642 -0.249642)
							(end -0.2794 -0.1778)
						)
						(arc
							(start -0.2794 0.1778)
							(mid -0.249642 0.249642)
							(end -0.1778 0.2794)
						)
						(arc
							(start 0.1778 0.2794)
							(mid 0.249642 0.249642)
							(end 0.2794 0.1778)
						)
						(arc
							(start 0.2794 -0.1778)
							(mid 0.249642 -0.249642)
							(end 0.1778 -0.2794)
						)
					)
					(width 0)
					(fill yes)
				)
			)
		)
		(pad "2" smd custom
			(at 0 0.4445)
			(size 0.1397 0.1397)
			(layers "F.Cu" "F.Mask" "F.Paste")
			(net "Q22_D")
			(options
				(clearance outline)
				(anchor circle)
			)
			(primitives
				(gr_poly
					(pts
						(arc
							(start -0.1778 -0.2794)
							(mid -0.249642 -0.249642)
							(end -0.2794 -0.1778)
						)
						(arc
							(start -0.2794 0.1778)
							(mid -0.249642 0.249642)
							(end -0.1778 0.2794)
						)
						(arc
							(start 0.1778 0.2794)
							(mid 0.249642 0.249642)
							(end 0.2794 0.1778)
						)
						(arc
							(start 0.2794 -0.1778)
							(mid 0.249642 -0.249642)
							(end 0.1778 -0.2794)
						)
					)
					(width 0)
					(fill yes)
				)
			)
		)
	)
	(footprint ""
		(layer "F.Cu")
		(at 145.149824 -112.148874 -90)
		(property "Reference" "L29"
			(at 0 0 270)
			(layer "F.SilkS")
			(hide yes)
			(effects
				(font
					(size 1.27 1.27)
				)
			)
		)
		(property "Value" "IND-2D2UH-179-GP"
			(at -4.699 -4.0132 270)
			(unlocked yes)
			(layer "F.Fab")
			(hide yes)
			(effects
				(font
					(size 1.016 1.016)
					(thickness 0.1524)
				)
			)
		)
		(property "Device Type" "L7066-1830-UH119"
			(at -4.699 -5.5372 270)
			(unlocked yes)
			(layer "F.Fab")
			(hide yes)
			(effects
				(font
					(size 1.016 1.016)
					(thickness 0.1524)
				)
			)
		)
		(duplicate_pad_numbers_are_jumpers no)
		(fp_line
			(start -3.556 4.4958)
			(end -3.556 -4.4958)
			(stroke
				(width 0.1524)
				(type default)
			)
			(layer "F.SilkS")
		)
		(fp_line
			(start 3.556 4.4958)
			(end -3.556 4.4958)
			(stroke
				(width 0.1524)
				(type default)
			)
			(layer "F.SilkS")
		)
		(fp_line
			(start -3.556 -4.4958)
			(end 3.556 -4.4958)
			(stroke
				(width 0.1524)
				(type default)
			)
			(layer "F.SilkS")
		)
		(fp_line
			(start 3.556 -4.4958)
			(end 3.556 4.4958)
			(stroke
				(width 0.1524)
				(type default)
			)
			(layer "F.SilkS")
		)
		(fp_rect
			(start -3.302 3.4798)
			(end 3.302 -3.4798)
			(stroke
				(width 0)
				(type default)
			)
			(fill no)
			(layer "F.CrtYd")
		)
		(fp_poly
			(pts
				(xy -3.81 4.572) (xy -3.81 -4.572) (xy 3.81 -4.572) (xy 3.81 -0.5588) (xy 3.302 -0.5588) (xy 3.302 -3.4798)
				(xy -3.302 -3.4798) (xy -3.302 3.4798) (xy 3.302 3.4798) (xy 3.302 -0.5461) (xy 3.81 -0.5461) (xy 3.81 4.572)
			)
			(stroke
				(width 0)
				(type default)
			)
			(fill no)
			(layer "F.CrtYd")
		)
		(fp_rect
			(start -3.81 4.572)
			(end 3.81 -4.572)
			(stroke
				(width 0)
				(type default)
			)
			(fill no)
			(layer "F.Fab")
		)
		(pad "1" smd rect
			(at 0 -2.779522 270)
			(size 3.5052 2.921)
			(layers "F.Cu" "F.Mask" "F.Paste")
			(net "P1V5_E_LL")
		)
		(pad "2" smd rect
			(at 0 2.779522 270)
			(size 3.5052 2.921)
			(layers "F.Cu" "F.Mask" "F.Paste")
			(net "P1V5_E_OUT")
		)
	)
	(footprint ""
		(layer "F.Cu")
		(at 189.2808 -24.003 -90)
		(property "Reference" "R258"
			(at 0 0 270)
			(layer "F.SilkS")
			(hide yes)
			(effects
				(font
					(size 1.27 1.27)
				)
			)
		)
		(property "Value" "4K7R2F-GP"
			(at 0.064008 -3.993896 270)
			(unlocked yes)
			(layer "F.Fab")
			(hide yes)
			(effects
				(font
					(size 1.016 1.016)
					(thickness 0.1524)
				)
			)
		)
		(property "Device Type" "R402H16"
			(at 0.064008 -5.517896 270)
			(unlocked yes)
			(layer "F.Fab")
			(hide yes)
			(effects
				(font
					(size 1.016 1.016)
					(thickness 0.1524)
				)
			)
		)
		(duplicate_pad_numbers_are_jumpers no)
		(fp_line
			(start -0.508 -0.9398)
			(end -0.508 0.9398)
			(stroke
				(width 0.1524)
				(type default)
			)
			(layer "F.SilkS")
		)
		(fp_line
			(start 0.508 -0.9398)
			(end -0.508 -0.9398)
			(stroke
				(width 0.1524)
				(type default)
			)
			(layer "F.SilkS")
		)
		(fp_rect
			(start -0.508 0.9398)
			(end 0.508 -0.9398)
			(stroke
				(width 0)
				(type default)
			)
			(fill no)
			(layer "F.CrtYd")
		)
		(fp_rect
			(start -0.508 0.9398)
			(end 0.508 -0.9398)
			(stroke
				(width 0)
				(type default)
			)
			(fill no)
			(layer "F.Fab")
		)
		(pad "1" smd custom
			(at 0 -0.4445 270)
			(size 0.1397 0.1397)
			(layers "F.Cu" "F.Mask" "F.Paste")
			(net "P1V8_C")
			(options
				(clearance outline)
				(anchor circle)
			)
			(primitives
				(gr_poly
					(pts
						(arc
							(start -0.1778 -0.2794)
							(mid -0.249642 -0.249642)
							(end -0.2794 -0.1778)
						)
						(arc
							(start -0.2794 0.1778)
							(mid -0.249642 0.249642)
							(end -0.1778 0.2794)
						)
						(arc
							(start 0.1778 0.2794)
							(mid 0.249642 0.249642)
							(end 0.2794 0.1778)
						)
						(arc
							(start 0.2794 -0.1778)
							(mid 0.249642 -0.249642)
							(end 0.1778 -0.2794)
						)
					)
					(width 0)
					(fill yes)
				)
			)
		)
		(pad "2" smd custom
			(at 0 0.4445 270)
			(size 0.1397 0.1397)
			(layers "F.Cu" "F.Mask" "F.Paste")
			(net "SYS_HALT0#")
			(options
				(clearance outline)
				(anchor circle)
			)
			(primitives
				(gr_poly
					(pts
						(arc
							(start -0.1778 -0.2794)
							(mid -0.249642 -0.249642)
							(end -0.2794 -0.1778)
						)
						(arc
							(start -0.2794 0.1778)
							(mid -0.249642 0.249642)
							(end -0.1778 0.2794)
						)
						(arc
							(start 0.1778 0.2794)
							(mid 0.249642 0.249642)
							(end 0.2794 0.1778)
						)
						(arc
							(start 0.2794 -0.1778)
							(mid 0.249642 -0.249642)
							(end 0.1778 -0.2794)
						)
					)
					(width 0)
					(fill yes)
				)
			)
		)
	)
	(footprint ""
		(layer "F.Cu")
		(at 47.573692 -36.92652 90)
		(property "Reference" "C616"
			(at 0 0 90)
			(layer "F.SilkS")
			(hide yes)
			(effects
				(font
					(size 1.27 1.27)
				)
			)
		)
		(property "Value" "SC4D7U25V5KX-1-GP"
			(at -0.0762 -6.1214 90)
			(unlocked yes)
			(layer "F.Fab")
			(hide yes)
			(effects
				(font
					(size 1.016 1.016)
					(thickness 0.1524)
				)
			)
		)
		(property "Device Type" "C805H58"
			(at -0.0762 -8.1534 90)
			(unlocked yes)
			(layer "F.Fab")
			(hide yes)
			(effects
				(font
					(size 1.016 1.016)
					(thickness 0.1524)
				)
			)
		)
		(duplicate_pad_numbers_are_jumpers no)
		(fp_line
			(start 0.635 0)
			(end -0.635 0)
			(stroke
				(width 0.508)
				(type default)
			)
			(layer "F.SilkS")
		)
		(fp_rect
			(start -0.9652 1.778)
			(end 0.9652 -1.778)
			(stroke
				(width 0)
				(type default)
			)
			(fill no)
			(layer "F.CrtYd")
		)
		(fp_poly
			(pts
				(xy -0.9652 -1.778) (xy 0.9652 -1.778) (xy 0.9652 1.778) (xy -0.9652 1.778)
			)
			(stroke
				(width 0)
				(type default)
			)
			(fill no)
			(layer "F.Fab")
		)
		(pad "1" smd rect
			(at 0 -0.9652 90)
			(size 1.397 1.143)
			(layers "F.Cu" "F.Mask" "F.Paste")
			(net "P0V9_V5")
		)
		(pad "2" smd rect
			(at 0 0.9652 90)
			(size 1.397 1.143)
			(layers "F.Cu" "F.Mask" "F.Paste")
			(net "GND")
		)
	)
	(footprint ""
		(layer "F.Cu")
		(at 9.525 -97.9678)
		(property "Reference" "R585"
			(at 0 0 0)
			(layer "F.SilkS")
			(hide yes)
			(effects
				(font
					(size 1.27 1.27)
				)
			)
		)
		(property "Value" "0R2J-2-GP"
			(at 0.064008 -3.993896 0)
			(unlocked yes)
			(layer "F.Fab")
			(hide yes)
			(effects
				(font
					(size 1.016 1.016)
					(thickness 0.1524)
				)
			)
		)
		(property "Device Type" "R402H16"
			(at 0.064008 -5.517896 0)
			(unlocked yes)
			(layer "F.Fab")
			(hide yes)
			(effects
				(font
					(size 1.016 1.016)
					(thickness 0.1524)
				)
			)
		)
		(duplicate_pad_numbers_are_jumpers no)
		(fp_line
			(start -0.508 -0.9398)
			(end -0.508 0.9398)
			(stroke
				(width 0.1524)
				(type default)
			)
			(layer "F.SilkS")
		)
		(fp_line
			(start 0.508 -0.9398)
			(end -0.508 -0.9398)
			(stroke
				(width 0.1524)
				(type default)
			)
			(layer "F.SilkS")
		)
		(fp_rect
			(start -0.508 0.9398)
			(end 0.508 -0.9398)
			(stroke
				(width 0)
				(type default)
			)
			(fill no)
			(layer "F.CrtYd")
		)
		(fp_rect
			(start -0.508 0.9398)
			(end 0.508 -0.9398)
			(stroke
				(width 0)
				(type default)
			)
			(fill no)
			(layer "F.Fab")
		)
		(pad "1" smd custom
			(at 0 -0.4445)
			(size 0.1397 0.1397)
			(layers "F.Cu" "F.Mask" "F.Paste")
			(net "SCC_FULL_PGOOD")
			(options
				(clearance outline)
				(anchor circle)
			)
			(primitives
				(gr_poly
					(pts
						(arc
							(start -0.1778 -0.2794)
							(mid -0.249642 -0.249642)
							(end -0.2794 -0.1778)
						)
						(arc
							(start -0.2794 0.1778)
							(mid -0.249642 0.249642)
							(end -0.1778 0.2794)
						)
						(arc
							(start 0.1778 0.2794)
							(mid 0.249642 0.249642)
							(end 0.2794 0.1778)
						)
						(arc
							(start 0.2794 -0.1778)
							(mid 0.249642 -0.249642)
							(end 0.1778 -0.2794)
						)
					)
					(width 0)
					(fill yes)
				)
			)
		)
		(pad "2" smd custom
			(at 0 0.4445)
			(size 0.1397 0.1397)
			(layers "F.Cu" "F.Mask" "F.Paste")
			(net "U120_EN")
			(options
				(clearance outline)
				(anchor circle)
			)
			(primitives
				(gr_poly
					(pts
						(arc
							(start -0.1778 -0.2794)
							(mid -0.249642 -0.249642)
							(end -0.2794 -0.1778)
						)
						(arc
							(start -0.2794 0.1778)
							(mid -0.249642 0.249642)
							(end -0.1778 0.2794)
						)
						(arc
							(start 0.1778 0.2794)
							(mid 0.249642 0.249642)
							(end 0.2794 0.1778)
						)
						(arc
							(start 0.2794 -0.1778)
							(mid 0.249642 -0.249642)
							(end 0.1778 -0.2794)
						)
					)
					(width 0)
					(fill yes)
				)
			)
		)
	)
)
